(kicad_pcb
	(version 20241229)
	(generator "pcbnew")
	(generator_version "9.0")
	(general
		(thickness 1.62)
		(legacy_teardrops no)
	)
	(paper "A3")
	(title_block
		(title "COM Express 7 Baseboard")
		(date "2025-02-04")
		(rev "1.1.2")
		(company "Antmicro Ltd")
		(comment 1 "www.antmicro.com")
		(comment 9 "footprints 770-774 of 802")
	)
	(layers
		(0 "F.Cu" signal)
		(4 "In1.Cu" signal)
		(6 "In2.Cu" signal)
		(8 "In3.Cu" signal)
		(10 "In4.Cu" signal)
		(12 "In5.Cu" signal)
		(14 "In6.Cu" signal)
		(2 "B.Cu" signal)
		(9 "F.Adhes" user "F.Adhesive")
		(11 "B.Adhes" user "B.Adhesive")
		(13 "F.Paste" user)
		(15 "B.Paste" user)
		(5 "F.SilkS" user "F.Silkscreen")
		(7 "B.SilkS" user "B.Silkscreen")
		(1 "F.Mask" user)
		(3 "B.Mask" user)
		(17 "Dwgs.User" user "User.Drawings")
		(19 "Cmts.User" user "User.Comments")
		(21 "Eco1.User" user "User.Eco1")
		(23 "Eco2.User" user "User.Eco2")
		(25 "Edge.Cuts" user)
		(27 "Margin" user)
		(31 "F.CrtYd" user "F.Courtyard")
		(29 "B.CrtYd" user "B.Courtyard")
		(35 "F.Fab" user)
		(33 "B.Fab" user)
	)
	(footprint "antmicro-footprints:C_0402_1005Metric"
		(layer "B.Cu")
		(at 115.314999 77.724999 180)
		(descr "Capacitor SMD 0402")
		(tags "capacitor SMD 0402")
		(property "Reference" "C33"
			(at 0.814999 -0.435001 0)
			(layer "B.SilkS")
			(effects
				(font
					(size 0.7 0.7)
					(thickness 0.15)
				)
				(justify left bottom mirror)
			)
		)
		(property "Value" "C_1u_0402"
			(at -1.022927 -2.155213 0)
			(layer "B.Fab")
			(effects
				(font
					(size 0.7 0.7)
					(thickness 0.15)
				)
				(justify left bottom mirror)
			)
		)
		(property "Datasheet" "https://product.tdk.com/en/search/capacitor/ceramic/mlcc/info?part_no=C1005X6S1A105K050BC"
			(at 0 0 180)
			(layer "F.Fab")
			(hide yes)
			(effects
				(font
					(size 1.27 1.27)
					(thickness 0.15)
				)
			)
		)
		(property "Author" "Antmicro"
			(at 230.629998 155.449998 0)
			(layer "B.Fab")
			(hide yes)
			(effects
				(font
					(size 1 1)
					(thickness 0.15)
				)
				(justify mirror)
			)
		)
		(property "Dielectric" ""
			(at 230.629998 155.449998 0)
			(layer "B.Fab")
			(hide yes)
			(effects
				(font
					(size 1 1)
					(thickness 0.15)
				)
				(justify mirror)
			)
		)
		(property "License" "Apache-2.0"
			(at 230.629998 155.449998 0)
			(layer "B.Fab")
			(hide yes)
			(effects
				(font
					(size 1 1)
					(thickness 0.15)
				)
				(justify mirror)
			)
		)
		(property "MPN" "C1005X6S1A105K050BC"
			(at 230.629998 155.449998 0)
			(layer "B.Fab")
			(hide yes)
			(effects
				(font
					(size 1 1)
					(thickness 0.15)
				)
				(justify mirror)
			)
		)
		(property "Manufacturer" "TDK"
			(at 230.629998 155.449998 0)
			(layer "B.Fab")
			(hide yes)
			(effects
				(font
					(size 1 1)
					(thickness 0.15)
				)
				(justify mirror)
			)
		)
		(property "Public" "False"
			(at 230.629998 155.449998 0)
			(layer "B.Fab")
			(hide yes)
			(effects
				(font
					(size 1 1)
					(thickness 0.15)
				)
				(justify mirror)
			)
		)
		(property "Val" "1u"
			(at 230.629998 155.449998 0)
			(layer "B.Fab")
			(hide yes)
			(effects
				(font
					(size 1 1)
					(thickness 0.15)
				)
				(justify mirror)
			)
		)
		(property "Voltage" ""
			(at 230.629998 155.449998 0)
			(layer "B.Fab")
			(hide yes)
			(effects
				(font
					(size 1 1)
					(thickness 0.15)
				)
				(justify mirror)
			)
		)
		(sheetname "USB-C console")
		(sheetfile "usb-c_console.kicad_sch")
		(attr smd)
		(fp_rect
			(start -0.925 0.47)
			(end 0.925 -0.47)
			(stroke
				(width 0.05)
				(type default)
			)
			(fill no)
			(layer "B.CrtYd")
		)
		(fp_line
			(start 0.504 0.25)
			(end -0.494 0.25)
			(stroke
				(width 0.15)
				(type solid)
			)
			(layer "B.Fab")
		)
		(fp_line
			(start 0.504 -0.248)
			(end 0.504 0.25)
			(stroke
				(width 0.15)
				(type solid)
			)
			(layer "B.Fab")
		)
		(fp_line
			(start -0.494 0.25)
			(end -0.494 -0.248)
			(stroke
				(width 0.15)
				(type solid)
			)
			(layer "B.Fab")
		)
		(fp_line
			(start -0.494 -0.248)
			(end 0.504 -0.248)
			(stroke
				(width 0.15)
				(type solid)
			)
			(layer "B.Fab")
		)
		(pad "1" smd roundrect
			(at -0.48 0 180)
			(size 0.59 0.64)
			(layers "B.Cu" "B.Mask" "B.Paste")
			(roundrect_rratio 0.25)
			(net 1 "GND")
			(pintype "passive")
			(teardrops
				(best_length_ratio 0.2)
				(max_length 1)
				(best_width_ratio 0.9)
				(max_width 2)
				(curved_edges yes)
				(filter_ratio 0.9)
				(enabled yes)
				(allow_two_segments yes)
				(prefer_zone_connections yes)
			)
		)
		(pad "2" smd roundrect
			(at 0.48 0 180)
			(size 0.59 0.64)
			(layers "B.Cu" "B.Mask" "B.Paste")
			(roundrect_rratio 0.25)
			(net 58 "/USB-C console/VBUS_FTDI")
			(pintype "passive")
			(teardrops
				(best_length_ratio 0.2)
				(max_length 1)
				(best_width_ratio 0.9)
				(max_width 2)
				(curved_edges yes)
				(filter_ratio 0.9)
				(enabled yes)
				(allow_two_segments yes)
				(prefer_zone_connections yes)
			)
		)
	)
	(footprint "antmicro-footprints:R_0402_1005Metric"
		(layer "B.Cu")
		(at 193 165.9 -90)
		(descr "Resistor SMD 0402")
		(tags "resistor SMD 0402")
		(property "Reference" "R162"
			(at 1.1 -0.4 90)
			(layer "B.SilkS")
			(effects
				(font
					(size 0.7 0.7)
					(thickness 0.15)
				)
				(justify left bottom mirror)
			)
		)
		(property "Value" "R_10k_0402"
			(at 2.213157 -54.437047 90)
			(layer "B.Fab")
			(hide yes)
			(effects
				(font
					(size 0.7 0.7)
					(thickness 0.15)
				)
				(justify left bottom mirror)
			)
		)
		(property "Datasheet" "https://www.bourns.com/docs/product-datasheets/cr.pdf"
			(at 0 0 90)
			(layer "F.Fab")
			(hide yes)
			(effects
				(font
					(size 1.27 1.27)
					(thickness 0.15)
				)
			)
		)
		(property "Author" "Antmicro"
			(at 426 315.67 90)
			(layer "B.Fab")
			(hide yes)
			(effects
				(font
					(size 1 1)
					(thickness 0.15)
				)
				(justify mirror)
			)
		)
		(property "License" "Apache-2.0"
			(at 426 315.67 90)
			(layer "B.Fab")
			(hide yes)
			(effects
				(font
					(size 1 1)
					(thickness 0.15)
				)
				(justify mirror)
			)
		)
		(property "MPN" "CR0402-FX-1002GLF"
			(at 426 315.67 90)
			(layer "B.Fab")
			(hide yes)
			(effects
				(font
					(size 1 1)
					(thickness 0.15)
				)
				(justify mirror)
			)
		)
		(property "Manufacturer" "Bourns"
			(at 426 315.67 90)
			(layer "B.Fab")
			(hide yes)
			(effects
				(font
					(size 1 1)
					(thickness 0.15)
				)
				(justify mirror)
			)
		)
		(property "Public" "False"
			(at 426 315.67 90)
			(layer "B.Fab")
			(hide yes)
			(effects
				(font
					(size 1 1)
					(thickness 0.15)
				)
				(justify mirror)
			)
		)
		(property "Tolerance" "1%"
			(at 426 315.67 90)
			(layer "B.Fab")
			(hide yes)
			(effects
				(font
					(size 1 1)
					(thickness 0.15)
				)
				(justify mirror)
			)
		)
		(property "Val" "10k"
			(at 426 315.67 90)
			(layer "B.Fab")
			(hide yes)
			(effects
				(font
					(size 1 1)
					(thickness 0.15)
				)
				(justify mirror)
			)
		)
		(sheetname "Com Express 7 MGMT")
		(sheetfile "com_express_7_mgmt.kicad_sch")
		(attr smd)
		(fp_rect
			(start -0.925 0.47)
			(end 0.925 -0.47)
			(stroke
				(width 0.05)
				(type default)
			)
			(fill no)
			(layer "B.CrtYd")
		)
		(fp_rect
			(start -0.5 0.25)
			(end 0.5 -0.25)
			(stroke
				(width 0.15)
				(type solid)
			)
			(fill no)
			(layer "B.Fab")
		)
		(pad "1" smd roundrect
			(at -0.48 0 270)
			(size 0.59 0.64)
			(layers "B.Cu" "B.Mask" "B.Paste")
			(roundrect_rratio 0.25)
			(net 373 "Net-(J12D-~{THRM})")
			(pintype "passive")
			(teardrops
				(best_length_ratio 0.2)
				(max_length 1)
				(best_width_ratio 0.9)
				(max_width 2)
				(curved_edges yes)
				(filter_ratio 0.9)
				(enabled yes)
				(allow_two_segments yes)
				(prefer_zone_connections yes)
			)
		)
		(pad "2" smd roundrect
			(at 0.48 0 270)
			(size 0.59 0.64)
			(layers "B.Cu" "B.Mask" "B.Paste")
			(roundrect_rratio 0.25)
			(net 2 "+3V3")
			(pintype "passive")
			(teardrops
				(best_length_ratio 0.2)
				(max_length 1)
				(best_width_ratio 0.9)
				(max_width 2)
				(curved_edges yes)
				(filter_ratio 0.9)
				(enabled yes)
				(allow_two_segments yes)
				(prefer_zone_connections yes)
			)
		)
	)
	(footprint "antmicro-footprints:C_0402_1005Metric"
		(layer "B.Cu")
		(at 195.711055 139.844794 135)
		(descr "Capacitor SMD 0402")
		(tags "capacitor SMD 0402")
		(property "Reference" "C130"
			(at -2.768935 0.013654 135)
			(layer "B.SilkS")
			(effects
				(font
					(size 0.7 0.7)
					(thickness 0.15)
				)
				(justify right bottom mirror)
			)
		)
		(property "Value" "C_220n_0402"
			(at -1.022927 -2.155213 135)
			(layer "B.Fab")
			(effects
				(font
					(size 0.7 0.7)
					(thickness 0.15)
				)
				(justify right bottom mirror)
			)
		)
		(property "Datasheet" "https://www.yageo.com/en/Chart/Download/pdf/CC0402KRX5R6BB224"
			(at 0 0 135)
			(layer "F.Fab")
			(hide yes)
			(effects
				(font
					(size 1.27 1.27)
					(thickness 0.15)
				)
			)
		)
		(property "Author" "Antmicro"
			(at 340.72 -40.099999 45)
			(layer "B.Fab")
			(hide yes)
			(effects
				(font
					(size 1 1)
					(thickness 0.15)
				)
				(justify mirror)
			)
		)
		(property "Dielectric" ""
			(at 340.72 -40.099999 45)
			(layer "B.Fab")
			(hide yes)
			(effects
				(font
					(size 1 1)
					(thickness 0.15)
				)
				(justify mirror)
			)
		)
		(property "License" "Apache-2.0"
			(at 340.72 -40.099999 45)
			(layer "B.Fab")
			(hide yes)
			(effects
				(font
					(size 1 1)
					(thickness 0.15)
				)
				(justify mirror)
			)
		)
		(property "MPN" "CC0402KRX5R6BB224"
			(at 340.72 -40.099999 45)
			(layer "B.Fab")
			(hide yes)
			(effects
				(font
					(size 1 1)
					(thickness 0.15)
				)
				(justify mirror)
			)
		)
		(property "Manufacturer" "YAGEO"
			(at 340.72 -40.099999 45)
			(layer "B.Fab")
			(hide yes)
			(effects
				(font
					(size 1 1)
					(thickness 0.15)
				)
				(justify mirror)
			)
		)
		(property "Public" "False"
			(at 340.72 -40.099999 45)
			(layer "B.Fab")
			(hide yes)
			(effects
				(font
					(size 1 1)
					(thickness 0.15)
				)
				(justify mirror)
			)
		)
		(property "Val" "220n"
			(at 340.72 -40.099999 45)
			(layer "B.Fab")
			(hide yes)
			(effects
				(font
					(size 1 1)
					(thickness 0.15)
				)
				(justify mirror)
			)
		)
		(property "Voltage" ""
			(at 340.72 -40.099999 45)
			(layer "B.Fab")
			(hide yes)
			(effects
				(font
					(size 1 1)
					(thickness 0.15)
				)
				(justify mirror)
			)
		)
		(sheetname "PCIe redriver")
		(sheetfile "pcie_redriver.kicad_sch")
		(attr smd)
		(fp_poly
			(pts
				(xy -0.925 0.47) (xy 0.925 0.47) (xy 0.925 -0.47) (xy -0.925 -0.47)
			)
			(stroke
				(width 0.05)
				(type default)
			)
			(fill no)
			(layer "B.CrtYd")
		)
		(fp_line
			(start 0.504 -0.248)
			(end 0.504 0.25)
			(stroke
				(width 0.15)
				(type solid)
			)
			(layer "B.Fab")
		)
		(fp_line
			(start 0.504 0.25)
			(end -0.494 0.25)
			(stroke
				(width 0.15)
				(type solid)
			)
			(layer "B.Fab")
		)
		(fp_line
			(start -0.494 -0.248)
			(end 0.504 -0.248)
			(stroke
				(width 0.15)
				(type solid)
			)
			(layer "B.Fab")
		)
		(fp_line
			(start -0.494 0.25)
			(end -0.494 -0.248)
			(stroke
				(width 0.15)
				(type solid)
			)
			(layer "B.Fab")
		)
		(pad "1" smd roundrect
			(at -0.48 0 135)
			(size 0.59 0.64)
			(layers "B.Cu" "B.Mask" "B.Paste")
			(roundrect_rratio 0.25)
			(net 214 "/Com Express 7 Interfaces/PCIe_{B1x4}.RX2+")
			(pintype "passive")
			(teardrops
				(best_length_ratio 0.2)
				(max_length 1)
				(best_width_ratio 0.9)
				(max_width 2)
				(curved_edges yes)
				(filter_ratio 0.9)
				(enabled yes)
				(allow_two_segments yes)
				(prefer_zone_connections yes)
			)
		)
		(pad "2" smd roundrect
			(at 0.48 0 135)
			(size 0.59 0.64)
			(layers "B.Cu" "B.Mask" "B.Paste")
			(roundrect_rratio 0.25)
			(net 959 "/PCIe redriver/PCIe_{I}_C.RX2+")
			(pintype "passive")
			(teardrops
				(best_length_ratio 0.2)
				(max_length 1)
				(best_width_ratio 0.9)
				(max_width 2)
				(curved_edges yes)
				(filter_ratio 0.9)
				(enabled yes)
				(allow_two_segments yes)
				(prefer_zone_connections yes)
			)
		)
	)
	(footprint "antmicro-footprints:C_0402_1005Metric"
		(layer "B.Cu")
		(at 123.74 138.01)
		(descr "Capacitor SMD 0402")
		(tags "capacitor SMD 0402")
		(property "Reference" "C175"
			(at -3.64 0.35 0)
			(layer "B.SilkS")
			(effects
				(font
					(size 0.7 0.7)
					(thickness 0.15)
				)
				(justify right bottom mirror)
			)
		)
		(property "Value" "C_100n_0402"
			(at -1.022927 -2.155213 0)
			(layer "B.Fab")
			(effects
				(font
					(size 0.7 0.7)
					(thickness 0.15)
				)
				(justify right bottom mirror)
			)
		)
		(property "Datasheet" "https://www.murata.com/products/productdetail?partno=GRM155R61H104KE14%23"
			(at 0 0 0)
			(layer "F.Fab")
			(hide yes)
			(effects
				(font
					(size 1.27 1.27)
					(thickness 0.15)
				)
			)
		)
		(property "Author" "Antmicro"
			(at 0 0 0)
			(layer "B.Fab")
			(hide yes)
			(effects
				(font
					(size 1 1)
					(thickness 0.15)
				)
				(justify mirror)
			)
		)
		(property "Dielectric" "X5R"
			(at 0 0 0)
			(layer "B.Fab")
			(hide yes)
			(effects
				(font
					(size 1 1)
					(thickness 0.15)
				)
				(justify mirror)
			)
		)
		(property "License" "Apache-2.0"
			(at 0 0 0)
			(layer "B.Fab")
			(hide yes)
			(effects
				(font
					(size 1 1)
					(thickness 0.15)
				)
				(justify mirror)
			)
		)
		(property "MPN" "GRM155R61H104KE14D"
			(at 0 0 0)
			(layer "B.Fab")
			(hide yes)
			(effects
				(font
					(size 1 1)
					(thickness 0.15)
				)
				(justify mirror)
			)
		)
		(property "Manufacturer" "Murata"
			(at 0 0 0)
			(layer "B.Fab")
			(hide yes)
			(effects
				(font
					(size 1 1)
					(thickness 0.15)
				)
				(justify mirror)
			)
		)
		(property "Public" "False"
			(at 0 0 0)
			(layer "B.Fab")
			(hide yes)
			(effects
				(font
					(size 1 1)
					(thickness 0.15)
				)
				(justify mirror)
			)
		)
		(property "Val" "100n"
			(at 0 0 0)
			(layer "B.Fab")
			(hide yes)
			(effects
				(font
					(size 1 1)
					(thickness 0.15)
				)
				(justify mirror)
			)
		)
		(property "Voltage" "50V"
			(at 0 0 0)
			(layer "B.Fab")
			(hide yes)
			(effects
				(font
					(size 1 1)
					(thickness 0.15)
				)
				(justify mirror)
			)
		)
		(sheetname "KR to SFI #2")
		(sheetfile "kr_sfi.kicad_sch")
		(attr smd)
		(fp_rect
			(start -0.925 0.47)
			(end 0.925 -0.47)
			(stroke
				(width 0.05)
				(type default)
			)
			(fill no)
			(layer "B.CrtYd")
		)
		(fp_line
			(start -0.494 -0.248)
			(end 0.504 -0.248)
			(stroke
				(width 0.15)
				(type solid)
			)
			(layer "B.Fab")
		)
		(fp_line
			(start -0.494 0.25)
			(end -0.494 -0.248)
			(stroke
				(width 0.15)
				(type solid)
			)
			(layer "B.Fab")
		)
		(fp_line
			(start 0.504 -0.248)
			(end 0.504 0.25)
			(stroke
				(width 0.15)
				(type solid)
			)
			(layer "B.Fab")
		)
		(fp_line
			(start 0.504 0.25)
			(end -0.494 0.25)
			(stroke
				(width 0.15)
				(type solid)
			)
			(layer "B.Fab")
		)
		(pad "1" smd roundrect
			(at -0.48 0)
			(size 0.59 0.64)
			(layers "B.Cu" "B.Mask" "B.Paste")
			(roundrect_rratio 0.25)
			(net 1 "GND")
			(pintype "passive")
			(teardrops
				(best_length_ratio 0.2)
				(max_length 1)
				(best_width_ratio 0.9)
				(max_width 2)
				(curved_edges yes)
				(filter_ratio 0.9)
				(enabled yes)
				(allow_two_segments yes)
				(prefer_zone_connections yes)
			)
		)
		(pad "2" smd roundrect
			(at 0.48 0)
			(size 0.59 0.64)
			(layers "B.Cu" "B.Mask" "B.Paste")
			(roundrect_rratio 0.25)
			(net 2 "+3V3")
			(pintype "passive")
			(teardrops
				(best_length_ratio 0.2)
				(max_length 1)
				(best_width_ratio 0.9)
				(max_width 2)
				(curved_edges yes)
				(filter_ratio 0.9)
				(enabled yes)
				(allow_two_segments yes)
				(prefer_zone_connections yes)
			)
		)
	)
	(footprint "antmicro-footprints:C_0402_1005Metric"
		(layer "B.Cu")
		(at 107.78 156.54 180)
		(descr "Capacitor SMD 0402")
		(tags "capacitor SMD 0402")
		(property "Reference" "C215"
			(at -3.68 -0.4 0)
			(layer "B.SilkS")
			(effects
				(font
					(size 0.7 0.7)
					(thickness 0.15)
				)
				(justify left bottom mirror)
			)
		)
		(property "Value" "C_100n_0402"
			(at -1.022927 -2.155213 0)
			(layer "B.Fab")
			(effects
				(font
					(size 0.7 0.7)
					(thickness 0.15)
				)
				(justify left bottom mirror)
			)
		)
		(property "Datasheet" "https://www.murata.com/products/productdetail?partno=GRM155R61H104KE14%23"
			(at 0 0 180)
			(layer "F.Fab")
			(hide yes)
			(effects
				(font
					(size 1.27 1.27)
					(thickness 0.15)
				)
			)
		)
		(property "Author" "Antmicro"
			(at 215.56 313.08 0)
			(layer "B.Fab")
			(hide yes)
			(effects
				(font
					(size 1 1)
					(thickness 0.15)
				)
				(justify mirror)
			)
		)
		(property "Dielectric" "X5R"
			(at 215.56 313.08 0)
			(layer "B.Fab")
			(hide yes)
			(effects
				(font
					(size 1 1)
					(thickness 0.15)
				)
				(justify mirror)
			)
		)
		(property "License" "Apache-2.0"
			(at 215.56 313.08 0)
			(layer "B.Fab")
			(hide yes)
			(effects
				(font
					(size 1 1)
					(thickness 0.15)
				)
				(justify mirror)
			)
		)
		(property "MPN" "GRM155R61H104KE14D"
			(at 215.56 313.08 0)
			(layer "B.Fab")
			(hide yes)
			(effects
				(font
					(size 1 1)
					(thickness 0.15)
				)
				(justify mirror)
			)
		)
		(property "Manufacturer" "Murata"
			(at 215.56 313.08 0)
			(layer "B.Fab")
			(hide yes)
			(effects
				(font
					(size 1 1)
					(thickness 0.15)
				)
				(justify mirror)
			)
		)
		(property "Public" "False"
			(at 215.56 313.08 0)
			(layer "B.Fab")
			(hide yes)
			(effects
				(font
					(size 1 1)
					(thickness 0.15)
				)
				(justify mirror)
			)
		)
		(property "Val" "100n"
			(at 215.56 313.08 0)
			(layer "B.Fab")
			(hide yes)
			(effects
				(font
					(size 1 1)
					(thickness 0.15)
				)
				(justify mirror)
			)
		)
		(property "Voltage" "50V"
			(at 215.56 313.08 0)
			(layer "B.Fab")
			(hide yes)
			(effects
				(font
					(size 1 1)
					(thickness 0.15)
				)
				(justify mirror)
			)
		)
		(sheetname "2xSFP+")
		(sheetfile "2xSFP+.kicad_sch")
		(attr smd)
		(fp_rect
			(start -0.925 0.47)
			(end 0.925 -0.47)
			(stroke
				(width 0.05)
				(type default)
			)
			(fill no)
			(layer "B.CrtYd")
		)
		(fp_line
			(start 0.504 0.25)
			(end -0.494 0.25)
			(stroke
				(width 0.15)
				(type solid)
			)
			(layer "B.Fab")
		)
		(fp_line
			(start 0.504 -0.248)
			(end 0.504 0.25)
			(stroke
				(width 0.15)
				(type solid)
			)
			(layer "B.Fab")
		)
		(fp_line
			(start -0.494 0.25)
			(end -0.494 -0.248)
			(stroke
				(width 0.15)
				(type solid)
			)
			(layer "B.Fab")
		)
		(fp_line
			(start -0.494 -0.248)
			(end 0.504 -0.248)
			(stroke
				(width 0.15)
				(type solid)
			)
			(layer "B.Fab")
		)
		(pad "1" smd roundrect
			(at -0.48 0 180)
			(size 0.59 0.64)
			(layers "B.Cu" "B.Mask" "B.Paste")
			(roundrect_rratio 0.25)
			(net 53 "/2xSFP+/SH")
			(pintype "passive")
			(teardrops
				(best_length_ratio 0.2)
				(max_length 1)
				(best_width_ratio 0.9)
				(max_width 2)
				(curved_edges yes)
				(filter_ratio 0.9)
				(enabled yes)
				(allow_two_segments yes)
				(prefer_zone_connections yes)
			)
		)
		(pad "2" smd roundrect
			(at 0.48 0 180)
			(size 0.59 0.64)
			(layers "B.Cu" "B.Mask" "B.Paste")
			(roundrect_rratio 0.25)
			(net 1 "GND")
			(pintype "passive")
			(teardrops
				(best_length_ratio 0.2)
				(max_length 1)
				(best_width_ratio 0.9)
				(max_width 2)
				(curved_edges yes)
				(filter_ratio 0.9)
				(enabled yes)
				(allow_two_segments yes)
				(prefer_zone_connections yes)
			)
		)
	)
)
